(kicad_pcb
	(version 20240108)
	(generator "pcbnew")
	(generator_version "8.0")
	(general
		(thickness 1.62)
		(legacy_teardrops no)
	)
	(paper "A4")
	(title_block
		(title "Jetson Orin Baseboard")
		(date "2025-03-12")
		(rev "1.3.4")
		(company "Antmicro Ltd")
		(comment 1 "www.antmicro.com")
		(comment 9 "footprints 547-551 of 677")
	)
	(layers
		(0 "F.Cu" signal)
		(1 "In1.Cu" signal)
		(2 "In2.Cu" signal)
		(3 "In3.Cu" signal)
		(4 "In4.Cu" jumper)
		(5 "In5.Cu" signal)
		(6 "In6.Cu" signal)
		(31 "B.Cu" signal)
		(32 "B.Adhes" user "B.Adhesive")
		(33 "F.Adhes" user "F.Adhesive")
		(34 "B.Paste" user)
		(35 "F.Paste" user)
		(36 "B.SilkS" user "B.Silkscreen")
		(37 "F.SilkS" user "F.Silkscreen")
		(38 "B.Mask" user)
		(39 "F.Mask" user)
		(40 "Dwgs.User" user "User.Drawings")
		(41 "Cmts.User" user "User.Comments")
		(42 "Eco1.User" user "User.Eco1")
		(43 "Eco2.User" user "User.Eco2")
		(44 "Edge.Cuts" user)
		(45 "Margin" user)
		(46 "B.CrtYd" user "B.Courtyard")
		(47 "F.CrtYd" user "F.Courtyard")
		(48 "B.Fab" user)
		(49 "F.Fab" user)
	)
	(footprint "antmicro-footprints:MS621FE-FL11E"
		(layer "B.Cu")
		(at 136.098313 72.77 -90)
		(property "Reference" "BT1"
			(at 0 5.25 90)
			(layer "B.SilkS")
			(effects
				(font
					(size 0.7 0.7)
					(thickness 0.15)
				)
				(justify left bottom mirror)
			)
		)
		(property "Value" "Battery_Holder_MS621FE-FL11E"
			(at -0.001 -6.2 90)
			(layer "B.Fab")
			(effects
				(font
					(size 0.7 0.7)
					(thickness 0.15)
				)
				(justify left bottom mirror)
			)
		)
		(property "Footprint" "antmicro-footprints:MS621FE-FL11E"
			(at 0 0 -90)
			(layer "F.Fab")
			(hide yes)
			(effects
				(font
					(size 1.27 1.27)
					(thickness 0.15)
				)
			)
		)
		(property "Datasheet" "https://www.sii.co.jp/en/me/datasheets/ms-rechargeable/ms621fe/"
			(at 0 0 -90)
			(layer "F.Fab")
			(hide yes)
			(effects
				(font
					(size 1.27 1.27)
					(thickness 0.15)
				)
			)
		)
		(property "Author" "Antmicro"
			(at 63.328313 208.868313 0)
			(layer "B.Fab")
			(hide yes)
			(effects
				(font
					(size 1 1)
					(thickness 0.15)
				)
				(justify mirror)
			)
		)
		(property "License" "Apache-2.0"
			(at 63.328313 208.868313 0)
			(layer "B.Fab")
			(hide yes)
			(effects
				(font
					(size 1 1)
					(thickness 0.15)
				)
				(justify mirror)
			)
		)
		(property "MPN" "MS621FE-FL11E"
			(at 63.328313 208.868313 0)
			(layer "B.Fab")
			(hide yes)
			(effects
				(font
					(size 1 1)
					(thickness 0.15)
				)
				(justify mirror)
			)
		)
		(property "Manufacturer" "Seiko Instruments"
			(at 63.328313 208.868313 0)
			(layer "B.Fab")
			(hide yes)
			(effects
				(font
					(size 1 1)
					(thickness 0.15)
				)
				(justify mirror)
			)
		)
		(sheetname "SoM")
		(sheetfile "som.kicad_sch")
		(attr smd)
		(fp_arc
			(start -1.2 2.15)
			(mid 0 -4.834)
			(end 1.2 2.15)
			(stroke
				(width 0.15)
				(type solid)
			)
			(layer "B.SilkS")
		)
		(fp_line
			(start -1.275 5.2)
			(end 1.275 5.2)
			(stroke
				(width 0.05)
				(type solid)
			)
			(layer "B.CrtYd")
		)
		(fp_line
			(start -1.275 2.425)
			(end -1.275 5.2)
			(stroke
				(width 0.05)
				(type solid)
			)
			(layer "B.CrtYd")
		)
		(fp_line
			(start 1.275 2.425)
			(end 1.275 5.2)
			(stroke
				(width 0.05)
				(type solid)
			)
			(layer "B.CrtYd")
		)
		(fp_arc
			(start -1.275 2.425)
			(mid 0 -5.143374)
			(end 1.275 2.425)
			(stroke
				(width 0.05)
				(type solid)
			)
			(layer "B.CrtYd")
		)
		(fp_line
			(start -0.8 5.05)
			(end 1.2 5.05)
			(stroke
				(width 0.15)
				(type solid)
			)
			(layer "B.Fab")
		)
		(fp_line
			(start -1.2 4.65)
			(end -0.8 5.05)
			(stroke
				(width 0.15)
				(type solid)
			)
			(layer "B.Fab")
		)
		(fp_line
			(start -1.2 2.04)
			(end -1.2 4.65)
			(stroke
				(width 0.15)
				(type solid)
			)
			(layer "B.Fab")
		)
		(fp_line
			(start 1.2 2.04)
			(end 1.2 5.05)
			(stroke
				(width 0.15)
				(type solid)
			)
			(layer "B.Fab")
		)
		(fp_circle
			(center -0.001 -1.25)
			(end -0.001 2.25)
			(stroke
				(width 0.15)
				(type solid)
			)
			(fill none)
			(layer "B.Fab")
		)
		(fp_text user "Author: Antmicro"
			(at -3.501 -9.4 90)
			(layer "B.Fab")
			(hide yes)
			(effects
				(font
					(size 0.7 0.7)
					(thickness 0.15)
				)
				(justify left bottom mirror)
			)
		)
		(fp_text user "${REFERENCE}"
			(at -3.501 -11.8 90)
			(layer "B.Fab")
			(hide yes)
			(effects
				(font
					(size 0.7 0.7)
					(thickness 0.15)
				)
				(justify left bottom mirror)
			)
		)
		(fp_text user "COPPER KEEPOUT"
			(at -0.2 3.14 180)
			(unlocked yes)
			(layer "B.Fab")
			(effects
				(font
					(size 0.4 0.4)
					(thickness 0.1)
				)
				(justify left bottom mirror)
			)
		)
		(fp_text user "License: Apache-2.0"
			(at -3.501 -8.2 90)
			(layer "B.Fab")
			(hide yes)
			(effects
				(font
					(size 0.7 0.7)
					(thickness 0.15)
				)
				(justify left bottom mirror)
			)
		)
		(pad "1" smd rect
			(at -0.75 4.05)
			(size 1.8 0.75)
			(layers "B.Cu" "B.Paste" "B.Mask")
			(net 732 "Net-(BT1-+)")
			(pinfunction "+")
			(pintype "passive")
		)
		(pad "2" smd rect
			(at 0.75 4.05)
			(size 1.8 0.75)
			(layers "B.Cu" "B.Paste" "B.Mask")
			(net 1 "GND")
			(pinfunction "-")
			(pintype "passive")
		)
		(zone
			(net 0)
			(net_name "")
			(layers "B.Cu" "B.CrtYd")
			(hatch edge 0.508)
			(connect_pads
				(clearance 0)
			)
			(min_thickness 0.254)
			(filled_areas_thickness no)
			(keepout
				(tracks allowed)
				(vias not_allowed)
				(pads not_allowed)
				(copperpour not_allowed)
				(footprints allowed)
			)
			(fill
				(thermal_gap 0.508)
				(thermal_bridge_width 0.508)
			)
			(polygon
				(pts
					(xy 138.598313 71.61) (xy 132.958313 71.61) (xy 132.958313 73.93) (xy 138.598313 73.93)
				)
			)
		)
	)
	(footprint "antmicro-footprints:TP_SMD_0.75mm"
		(layer "B.Cu")
		(at 108.065 115.435)
		(property "Reference" "TP31"
			(at 0.42 0.385 90)
			(layer "B.SilkS")
			(effects
				(font
					(size 0.7 0.7)
					(thickness 0.15)
				)
				(justify left bottom mirror)
			)
		)
		(property "Value" "TP_0.75mm_SMD"
			(at 0 -1.2 0)
			(layer "B.Fab")
			(effects
				(font
					(size 0.7 0.7)
					(thickness 0.15)
				)
				(justify right bottom mirror)
			)
		)
		(property "Footprint" "antmicro-footprints:TP_SMD_0.75mm"
			(at 0 0 0)
			(layer "F.Fab")
			(hide yes)
			(effects
				(font
					(size 1.27 1.27)
					(thickness 0.15)
				)
			)
		)
		(property "Author" "Antmicro"
			(at 0 0 0)
			(layer "B.Fab")
			(hide yes)
			(effects
				(font
					(size 1 1)
					(thickness 0.15)
				)
				(justify mirror)
			)
		)
		(property "License" "Apache-2.0"
			(at 0 0 0)
			(layer "B.Fab")
			(hide yes)
			(effects
				(font
					(size 1 1)
					(thickness 0.15)
				)
				(justify mirror)
			)
		)
		(property "MPN" ""
			(at 0 0 0)
			(layer "B.Fab")
			(hide yes)
			(effects
				(font
					(size 1 1)
					(thickness 0.15)
				)
				(justify mirror)
			)
		)
		(property "Manufacturer" ""
			(at 0 0 0)
			(layer "B.Fab")
			(hide yes)
			(effects
				(font
					(size 1 1)
					(thickness 0.15)
				)
				(justify mirror)
			)
		)
		(sheetname "USB3")
		(sheetfile "usb3.kicad_sch")
		(attr exclude_from_pos_files exclude_from_bom)
		(fp_circle
			(center 0 0)
			(end 0.475 0)
			(stroke
				(width 0.05)
				(type default)
			)
			(fill none)
			(layer "B.CrtYd")
		)
		(fp_text user "License: Apache-2.0"
			(at -0.4 -5.101 0)
			(layer "B.Fab")
			(hide yes)
			(effects
				(font
					(size 0.7 0.7)
					(thickness 0.15)
				)
				(justify right bottom mirror)
			)
		)
		(fp_text user "Author: Antmicro"
			(at -0.4 -3.901 0)
			(layer "B.Fab")
			(hide yes)
			(effects
				(font
					(size 0.7 0.7)
					(thickness 0.15)
				)
				(justify right bottom mirror)
			)
		)
		(fp_text user "${REFERENCE}"
			(at -0.4 -2.7 0)
			(layer "B.Fab")
			(hide yes)
			(effects
				(font
					(size 0.7 0.7)
					(thickness 0.15)
				)
				(justify right bottom mirror)
			)
		)
		(pad "1" smd circle
			(at 0 0)
			(size 0.75 0.75)
			(layers "B.Cu" "B.Mask")
			(net 284 "/USB3/USBC1_ID")
			(pinfunction "1")
			(pintype "passive")
		)
	)
	(footprint "antmicro-footprints:C_0402_1005Metric"
		(layer "B.Cu")
		(at 71.8 101.9)
		(descr "Capacitor SMD 0402")
		(tags "capacitor SMD 0402")
		(property "Reference" "C59"
			(at 0.77 -1.5 180)
			(layer "B.SilkS")
			(effects
				(font
					(size 0.7 0.7)
					(thickness 0.15)
				)
				(justify left bottom mirror)
			)
		)
		(property "Value" "C_10u_0402"
			(at -1.022927 -2.155213 180)
			(layer "B.Fab")
			(effects
				(font
					(size 0.7 0.7)
					(thickness 0.15)
				)
				(justify left bottom mirror)
			)
		)
		(property "Footprint" "antmicro-footprints:C_0402_1005Metric"
			(at 0 0 0)
			(layer "F.Fab")
			(hide yes)
			(effects
				(font
					(size 1.27 1.27)
					(thickness 0.15)
				)
			)
		)
		(property "Datasheet" "https://www.yageo.com/en/Chart/Download/pdf/CC0402MRX5R5BB106"
			(at 0 0 0)
			(layer "F.Fab")
			(hide yes)
			(effects
				(font
					(size 1.27 1.27)
					(thickness 0.15)
				)
			)
		)
		(property "Author" "Antmicro"
			(at 0 0 0)
			(layer "B.Fab")
			(hide yes)
			(effects
				(font
					(size 1 1)
					(thickness 0.15)
				)
				(justify mirror)
			)
		)
		(property "Dielectric" ""
			(at 0 0 0)
			(layer "B.Fab")
			(hide yes)
			(effects
				(font
					(size 1 1)
					(thickness 0.15)
				)
				(justify mirror)
			)
		)
		(property "License" "Apache-2.0"
			(at 0 0 0)
			(layer "B.Fab")
			(hide yes)
			(effects
				(font
					(size 1 1)
					(thickness 0.15)
				)
				(justify mirror)
			)
		)
		(property "MPN" "CC0402MRX5R5BB106"
			(at 0 0 0)
			(layer "B.Fab")
			(hide yes)
			(effects
				(font
					(size 1 1)
					(thickness 0.15)
				)
				(justify mirror)
			)
		)
		(property "Manufacturer" "YAGEO"
			(at 0 0 0)
			(layer "B.Fab")
			(hide yes)
			(effects
				(font
					(size 1 1)
					(thickness 0.15)
				)
				(justify mirror)
			)
		)
		(property "Val" "10u"
			(at 0 0 0)
			(layer "B.Fab")
			(hide yes)
			(effects
				(font
					(size 1 1)
					(thickness 0.15)
				)
				(justify mirror)
			)
		)
		(property "Voltage" ""
			(at 0 0 0)
			(layer "B.Fab")
			(hide yes)
			(effects
				(font
					(size 1 1)
					(thickness 0.15)
				)
				(justify mirror)
			)
		)
		(sheetname "USB Debug, DP")
		(sheetfile "usb.kicad_sch")
		(attr smd)
		(fp_rect
			(start -0.925 0.47)
			(end 0.925 -0.47)
			(stroke
				(width 0.05)
				(type default)
			)
			(fill none)
			(layer "B.CrtYd")
		)
		(fp_line
			(start -0.494 -0.248)
			(end 0.504 -0.248)
			(stroke
				(width 0.15)
				(type solid)
			)
			(layer "B.Fab")
		)
		(fp_line
			(start -0.494 0.25)
			(end -0.494 -0.248)
			(stroke
				(width 0.15)
				(type solid)
			)
			(layer "B.Fab")
		)
		(fp_line
			(start 0.504 -0.248)
			(end 0.504 0.25)
			(stroke
				(width 0.15)
				(type solid)
			)
			(layer "B.Fab")
		)
		(fp_line
			(start 0.504 0.25)
			(end -0.494 0.25)
			(stroke
				(width 0.15)
				(type solid)
			)
			(layer "B.Fab")
		)
		(fp_text user "Author: Antmicro"
			(at -0.939 -3.399 180)
			(layer "B.Fab")
			(hide yes)
			(effects
				(font
					(size 0.7 0.7)
					(thickness 0.15)
				)
				(justify left bottom mirror)
			)
		)
		(fp_text user "${REFERENCE}"
			(at -0.939 -4.599 180)
			(layer "B.Fab")
			(hide yes)
			(effects
				(font
					(size 0.7 0.7)
					(thickness 0.15)
				)
				(justify left bottom mirror)
			)
		)
		(fp_text user "License: Apache-2.0"
			(at -0.939 -5.799 180)
			(layer "B.Fab")
			(hide yes)
			(effects
				(font
					(size 0.7 0.7)
					(thickness 0.15)
				)
				(justify left bottom mirror)
			)
		)
		(pad "1" smd roundrect
			(at -0.48 0)
			(size 0.59 0.64)
			(layers "B.Cu" "B.Paste" "B.Mask")
			(roundrect_rratio 0.25)
			(net 99 "+5V")
			(pintype "passive")
		)
		(pad "2" smd roundrect
			(at 0.48 0)
			(size 0.59 0.64)
			(layers "B.Cu" "B.Paste" "B.Mask")
			(roundrect_rratio 0.25)
			(net 1 "GND")
			(pintype "passive")
		)
	)
	(footprint "antmicro-footprints:C_0402_1005Metric"
		(layer "B.Cu")
		(at 57.55 111.45)
		(descr "Capacitor SMD 0402")
		(tags "capacitor SMD 0402")
		(property "Reference" "C29"
			(at 3.01 0.31 180)
			(layer "B.SilkS")
			(effects
				(font
					(size 0.7 0.7)
					(thickness 0.15)
				)
				(justify left bottom mirror)
			)
		)
		(property "Value" "C_100n_0402"
			(at 0 -1.4 180)
			(layer "B.Fab")
			(effects
				(font
					(size 0.7 0.7)
					(thickness 0.15)
				)
				(justify left bottom mirror)
			)
		)
		(property "Footprint" "antmicro-footprints:C_0402_1005Metric"
			(at 0 0 0)
			(layer "F.Fab")
			(hide yes)
			(effects
				(font
					(size 1.27 1.27)
					(thickness 0.15)
				)
			)
		)
		(property "Datasheet" "https://www.murata.com/products/productdetail?partno=GRM155R61H104KE14%23"
			(at 0 0 0)
			(layer "F.Fab")
			(hide yes)
			(effects
				(font
					(size 1.27 1.27)
					(thickness 0.15)
				)
			)
		)
		(property "Author" "Antmicro"
			(at 0 0 0)
			(layer "B.Fab")
			(hide yes)
			(effects
				(font
					(size 1 1)
					(thickness 0.15)
				)
				(justify mirror)
			)
		)
		(property "Dielectric" "X5R"
			(at 0 0 0)
			(layer "B.Fab")
			(hide yes)
			(effects
				(font
					(size 1 1)
					(thickness 0.15)
				)
				(justify mirror)
			)
		)
		(property "License" "Apache-2.0"
			(at 0 0 0)
			(layer "B.Fab")
			(hide yes)
			(effects
				(font
					(size 1 1)
					(thickness 0.15)
				)
				(justify mirror)
			)
		)
		(property "MPN" "GRM155R61H104KE14D"
			(at 0 0 0)
			(layer "B.Fab")
			(hide yes)
			(effects
				(font
					(size 1 1)
					(thickness 0.15)
				)
				(justify mirror)
			)
		)
		(property "Manufacturer" "Murata"
			(at 0 0 0)
			(layer "B.Fab")
			(hide yes)
			(effects
				(font
					(size 1 1)
					(thickness 0.15)
				)
				(justify mirror)
			)
		)
		(property "Val" "100n"
			(at 0 0 0)
			(layer "B.Fab")
			(hide yes)
			(effects
				(font
					(size 1 1)
					(thickness 0.15)
				)
				(justify mirror)
			)
		)
		(property "Voltage" "50V"
			(at 0 0 0)
			(layer "B.Fab")
			(hide yes)
			(effects
				(font
					(size 1 1)
					(thickness 0.15)
				)
				(justify mirror)
			)
		)
		(sheetname "USB Debug, DP")
		(sheetfile "usb.kicad_sch")
		(attr smd)
		(fp_rect
			(start -0.925 0.47)
			(end 0.925 -0.47)
			(stroke
				(width 0.05)
				(type default)
			)
			(fill none)
			(layer "B.CrtYd")
		)
		(fp_line
			(start -0.494 -0.248)
			(end 0.504 -0.248)
			(stroke
				(width 0.15)
				(type solid)
			)
			(layer "B.Fab")
		)
		(fp_line
			(start -0.494 0.25)
			(end -0.494 -0.248)
			(stroke
				(width 0.15)
				(type solid)
			)
			(layer "B.Fab")
		)
		(fp_line
			(start 0.504 -0.248)
			(end 0.504 0.25)
			(stroke
				(width 0.15)
				(type solid)
			)
			(layer "B.Fab")
		)
		(fp_line
			(start 0.504 0.25)
			(end -0.494 0.25)
			(stroke
				(width 0.15)
				(type solid)
			)
			(layer "B.Fab")
		)
		(fp_text user "${REFERENCE}"
			(at -0.932 -3.168 180)
			(layer "B.Fab")
			(hide yes)
			(effects
				(font
					(size 0.7 0.7)
					(thickness 0.15)
				)
				(justify left bottom mirror)
			)
		)
		(fp_text user "License: Apache-2.0"
			(at -0.932 -5.17 180)
			(layer "B.Fab")
			(hide yes)
			(effects
				(font
					(size 0.7 0.7)
					(thickness 0.15)
				)
				(justify left bottom mirror)
			)
		)
		(fp_text user "Author: Antmicro"
			(at -0.932 -4.17 180)
			(layer "B.Fab")
			(hide yes)
			(effects
				(font
					(size 0.7 0.7)
					(thickness 0.15)
				)
				(justify left bottom mirror)
			)
		)
		(pad "1" smd roundrect
			(at -0.48 0)
			(size 0.59 0.64)
			(layers "B.Cu" "B.Paste" "B.Mask")
			(roundrect_rratio 0.25)
			(net 185 "/USB Debug, DP/FTDI_3V3")
			(pintype "passive")
		)
		(pad "2" smd roundrect
			(at 0.48 0)
			(size 0.59 0.64)
			(layers "B.Cu" "B.Paste" "B.Mask")
			(roundrect_rratio 0.25)
			(net 1 "GND")
			(pintype "passive")
		)
	)
	(footprint "antmicro-footprints:R_0402_1005Metric"
		(layer "B.Cu")
		(at 60.14 98.62 90)
		(descr "Resistor SMD 0402")
		(tags "resistor SMD 0402")
		(property "Reference" "R71"
			(at -3.03 0.48 90)
			(layer "B.SilkS")
			(effects
				(font
					(size 0.7 0.7)
					(thickness 0.15)
				)
				(justify right bottom mirror)
			)
		)
		(property "Value" "R_0R_0402"
			(at 0 -1.4 90)
			(layer "B.Fab")
			(effects
				(font
					(size 0.7 0.7)
					(thickness 0.15)
				)
				(justify right bottom mirror)
			)
		)
		(property "Footprint" "antmicro-footprints:R_0402_1005Metric"
			(at 0 0 90)
			(layer "F.Fab")
			(hide yes)
			(effects
				(font
					(size 1.27 1.27)
					(thickness 0.15)
				)
			)
		)
		(property "Datasheet" "https://industrial.panasonic.com/cdbs/www-data/pdf/RDA0000/AOA0000C301.pdf"
			(at 0 0 90)
			(layer "F.Fab")
			(hide yes)
			(effects
				(font
					(size 1.27 1.27)
					(thickness 0.15)
				)
			)
		)
		(property "Author" "Antmicro"
			(at 158.76 38.48 0)
			(layer "B.Fab")
			(hide yes)
			(effects
				(font
					(size 1 1)
					(thickness 0.15)
				)
				(justify mirror)
			)
		)
		(property "Current" "1A"
			(at 158.76 38.48 0)
			(layer "B.Fab")
			(hide yes)
			(effects
				(font
					(size 1 1)
					(thickness 0.15)
				)
				(justify mirror)
			)
		)
		(property "License" "Apache-2.0"
			(at 158.76 38.48 0)
			(layer "B.Fab")
			(hide yes)
			(effects
				(font
					(size 1 1)
					(thickness 0.15)
				)
				(justify mirror)
			)
		)
		(property "MPN" "ERJ2GE0R00X"
			(at 158.76 38.48 0)
			(layer "B.Fab")
			(hide yes)
			(effects
				(font
					(size 1 1)
					(thickness 0.15)
				)
				(justify mirror)
			)
		)
		(property "Manufacturer" "Panasonic"
			(at 158.76 38.48 0)
			(layer "B.Fab")
			(hide yes)
			(effects
				(font
					(size 1 1)
					(thickness 0.15)
				)
				(justify mirror)
			)
		)
		(property "Tolerance" ""
			(at 158.76 38.48 0)
			(layer "B.Fab")
			(hide yes)
			(effects
				(font
					(size 1 1)
					(thickness 0.15)
				)
				(justify mirror)
			)
		)
		(property "Val" "0R"
			(at 158.76 38.48 0)
			(layer "B.Fab")
			(hide yes)
			(effects
				(font
					(size 1 1)
					(thickness 0.15)
				)
				(justify mirror)
			)
		)
		(sheetname "USB Debug, DP")
		(sheetfile "usb.kicad_sch")
		(attr smd)
		(fp_rect
			(start -0.925 0.47)
			(end 0.925 -0.47)
			(stroke
				(width 0.05)
				(type default)
			)
			(fill none)
			(layer "B.CrtYd")
		)
		(fp_rect
			(start -0.5 0.25)
			(end 0.5 -0.25)
			(stroke
				(width 0.15)
				(type solid)
			)
			(fill none)
			(layer "B.Fab")
		)
		(fp_text user "Author: Antmicro"
			(at -0.95 -4.169 90)
			(layer "B.Fab")
			(hide yes)
			(effects
				(font
					(size 0.7 0.7)
					(thickness 0.15)
				)
				(justify right bottom mirror)
			)
		)
		(fp_text user "${REFERENCE}"
			(at -0.95 -3.168 90)
			(layer "B.Fab")
			(hide yes)
			(effects
				(font
					(size 0.7 0.7)
					(thickness 0.15)
				)
				(justify right bottom mirror)
			)
		)
		(fp_text user "License: Apache-2.0"
			(at -0.95 -5.169 90)
			(layer "B.Fab")
			(hide yes)
			(effects
				(font
					(size 0.7 0.7)
					(thickness 0.15)
				)
				(justify right bottom mirror)
			)
		)
		(pad "1" smd roundrect
			(at -0.48 0 90)
			(size 0.59 0.64)
			(layers "B.Cu" "B.Paste" "B.Mask")
			(roundrect_rratio 0.25)
			(net 251 "SYS_SDA")
			(pintype "passive")
		)
		(pad "2" smd roundrect
			(at 0.48 0 90)
			(size 0.59 0.64)
			(layers "B.Cu" "B.Paste" "B.Mask")
			(roundrect_rratio 0.25)
			(net 303 "/USB Debug, DP/PDC_I2C1_SDA")
			(pintype "passive")
		)
	)
)
